# T6G (Grand Teton) — schematic netlist excerpt (pin names and nets, part order shuffled) for the footprints in the layout excerpt that follows; sources: Cadence DE-HDL packaged netlist, KiCad conversion of 04192023_DAF0TMB3IC0_F0TG_MB_C_brd_V02_OCP.brd

PR2516  Q_RES  10 1% CHIP  pkg 0402LF  page 266 : A = P12V_HSC_ADC_N ; B = P12V_HSC_SENSE2_R2_N
PR367  Q_RES  0 5% CHIP  pkg 0402LF  page 199 : A = PVDDCR_SOC_P0_VOS3 ; B = PVDDCR_SOC_P0
R1382  Q_RES  4.7K 5% CHIP  pkg 0201LF  page 185 : A = P1V8_CPU0_RT_1D ; B = SMB_RT_CPU0_P2_ROM_MUX_2D_R_SDA

(kicad_pcb
	(version 20260206)
	(generator "pcbnew")
	(generator_version "10.0")
	(general
		(thickness 1.6)
		(legacy_teardrops no)
	)
	(paper "A4")
	(title_block
		(title "04192023_DAF0TMB3IC0_F0TG_MB_C_brd_V02_OCP.brd")
		(comment 1 "Grand Teton / footprints 5101-5103 of 8354")
	)
	(layers
		(0 "F.Cu" signal "TOP")
		(4 "In1.Cu" signal "GND")
		(6 "In2.Cu" signal "IN1")
		(8 "In3.Cu" signal "GND1")
		(10 "In4.Cu" signal "IN2")
		(12 "In5.Cu" signal "GND2")
		(14 "In6.Cu" signal "IN3")
		(16 "In7.Cu" signal "GND3")
		(18 "In8.Cu" signal "VCC")
		(20 "In9.Cu" signal "VCC1")
		(22 "In10.Cu" signal "GND4")
		(24 "In11.Cu" signal "IN4")
		(26 "In12.Cu" signal "GND5")
		(28 "In13.Cu" signal "IN5")
		(30 "In14.Cu" signal "GND6")
		(32 "In15.Cu" signal "IN6")
		(34 "In16.Cu" signal "GND7")
		(2 "B.Cu" signal "BOTTOM")
		(9 "F.Adhes" user "F.Adhesive")
		(11 "B.Adhes" user "B.Adhesive")
		(13 "F.Paste" user "Package Geometry/Pastemask Top")
		(15 "B.Paste" user "Package Geometry/Pastemask Bottom")
		(5 "F.SilkS" user "Ref Des/Silkscreen Top")
		(7 "B.SilkS" user "Ref Des/Silkscreen Bottom")
		(1 "F.Mask" user "Board Geometry/Soldermask Top")
		(3 "B.Mask" user "Board Geometry/Soldermask Bottom")
		(17 "Dwgs.User" user "User.Drawings")
		(19 "Cmts.User" user "User.Comments")
		(21 "Eco1.User" user "User.Eco1")
		(23 "Eco2.User" user "User.Eco2")
		(25 "Edge.Cuts" user "Board Geometry/Outline")
		(27 "Margin" user)
		(31 "F.CrtYd" user "Package Geometry/Place Bound Top")
		(29 "B.CrtYd" user "Package Geometry/Place Bound Bottom")
		(35 "F.Fab" user "Ref Des/Assembly Top")
		(33 "B.Fab" user "Ref Des/Assembly Bottom")
	)
	(footprint ""
		(layer "B.Cu")
		(at 208.461356 -386.152136)
		(property "Reference" "PR2516"
			(at 0 0 0)
			(layer "B.SilkS")
			(hide yes)
			(effects
				(font
					(size 1.27 1.27)
				)
				(justify mirror)
			)
		)
		(property "Value" ""
			(at 0 0 0)
			(layer "B.Fab")
			(effects
				(font
					(size 1.27 1.27)
				)
				(justify mirror)
			)
		)
		(duplicate_pad_numbers_are_jumpers no)
		(fp_line
			(start -0.7874 -0.4064)
			(end -0.7874 0.4064)
			(stroke
				(width 0.1524)
				(type default)
			)
			(layer "B.SilkS")
		)
		(fp_line
			(start -0.7874 0.4064)
			(end 0.7874 0.4064)
			(stroke
				(width 0.1524)
				(type default)
			)
			(layer "B.SilkS")
		)
		(fp_line
			(start 0.7874 -0.4064)
			(end -0.7874 -0.4064)
			(stroke
				(width 0.1524)
				(type default)
			)
			(layer "B.SilkS")
		)
		(fp_line
			(start 0.7874 0.4064)
			(end 0.7874 -0.4064)
			(stroke
				(width 0.1524)
				(type default)
			)
			(layer "B.SilkS")
		)
		(fp_line
			(start -0.67945 -0.3048)
			(end -0.67945 0.3048)
			(stroke
				(width 0.1)
				(type default)
			)
			(layer "B.Fab")
		)
		(fp_line
			(start -0.67945 0.3048)
			(end -0.120396 0.3048)
			(stroke
				(width 0.1)
				(type default)
			)
			(layer "B.Fab")
		)
		(fp_line
			(start -0.12065 -0.3048)
			(end -0.67945 -0.3048)
			(stroke
				(width 0.1)
				(type default)
			)
			(layer "B.Fab")
		)
		(fp_line
			(start -0.12065 -0.2794)
			(end -0.12065 -0.3048)
			(stroke
				(width 0.1)
				(type default)
			)
			(layer "B.Fab")
		)
		(fp_line
			(start -0.120396 0.2794)
			(end 0.12065 0.2794)
			(stroke
				(width 0.1)
				(type default)
			)
			(layer "B.Fab")
		)
		(fp_line
			(start -0.120396 0.3048)
			(end -0.120396 0.2794)
			(stroke
				(width 0.1)
				(type default)
			)
			(layer "B.Fab")
		)
		(fp_line
			(start 0.12065 -0.305054)
			(end 0.12065 -0.2794)
			(stroke
				(width 0.1)
				(type default)
			)
			(layer "B.Fab")
		)
		(fp_line
			(start 0.12065 -0.2794)
			(end -0.12065 -0.2794)
			(stroke
				(width 0.1)
				(type default)
			)
			(layer "B.Fab")
		)
		(fp_line
			(start 0.12065 0.2794)
			(end 0.12065 0.3048)
			(stroke
				(width 0.1)
				(type default)
			)
			(layer "B.Fab")
		)
		(fp_line
			(start 0.12065 0.3048)
			(end 0.67945 0.3048)
			(stroke
				(width 0.1)
				(type default)
			)
			(layer "B.Fab")
		)
		(fp_line
			(start 0.67945 -0.305054)
			(end 0.12065 -0.305054)
			(stroke
				(width 0.1)
				(type default)
			)
			(layer "B.Fab")
		)
		(fp_line
			(start 0.67945 0.3048)
			(end 0.67945 -0.305054)
			(stroke
				(width 0.1)
				(type default)
			)
			(layer "B.Fab")
		)
		(pad "1" smd circle
			(at 0.40005 0 180)
			(size 0 0)
			(layers "B.Cu" "B.Mask" "B.Paste")
			(net "P12V_HSC_ADC_N")
		)
		(pad "2" smd circle
			(at -0.40005 0 180)
			(size 0 0)
			(layers "B.Cu" "B.Mask" "B.Paste")
			(net "P12V_HSC_SENSE2_R2_N")
		)
	)
	(footprint ""
		(layer "B.Cu")
		(at 254.635 -335.13268 180)
		(property "Reference" "R1382"
			(at 0 0 0)
			(layer "B.SilkS")
			(hide yes)
			(effects
				(font
					(size 1.27 1.27)
				)
				(justify mirror)
			)
		)
		(property "Value" ""
			(at 0 0 0)
			(layer "B.Fab")
			(effects
				(font
					(size 1.27 1.27)
				)
				(justify mirror)
			)
		)
		(duplicate_pad_numbers_are_jumpers no)
		(fp_line
			(start 0.32512 0.175006)
			(end 0.32512 -0.175006)
			(stroke
				(width 0.1)
				(type default)
			)
			(layer "B.Fab")
		)
		(fp_line
			(start 0.32512 -0.175006)
			(end -0.32512 -0.175006)
			(stroke
				(width 0.1)
				(type default)
			)
			(layer "B.Fab")
		)
		(fp_line
			(start -0.32512 0.175006)
			(end 0.32512 0.175006)
			(stroke
				(width 0.1)
				(type default)
			)
			(layer "B.Fab")
		)
		(fp_line
			(start -0.32512 -0.175006)
			(end -0.32512 0.175006)
			(stroke
				(width 0.1)
				(type default)
			)
			(layer "B.Fab")
		)
		(pad "1" smd rect
			(at 0.2667 0)
			(size 0.3048 0.381)
			(layers "B.Cu" "B.Mask" "B.Paste")
			(net "P1V8_CPU0_RT_1D")
		)
		(pad "2" smd rect
			(at -0.2667 0 180)
			(size 0.3048 0.381)
			(layers "B.Cu" "B.Mask" "B.Paste")
			(net "SMB_RT_CPU0_P2_ROM_MUX_2D_R_SDA")
		)
	)
	(footprint ""
		(layer "B.Cu")
		(at 418.191188 -161.102548 90)
		(property "Reference" "PR367"
			(at 0 0 90)
			(layer "B.SilkS")
			(hide yes)
			(effects
				(font
					(size 1.27 1.27)
				)
				(justify mirror)
			)
		)
		(property "Value" ""
			(at 0 0 90)
			(layer "B.Fab")
			(effects
				(font
					(size 1.27 1.27)
				)
				(justify mirror)
			)
		)
		(duplicate_pad_numbers_are_jumpers no)
		(fp_line
			(start 0.7874 -0.4064)
			(end -0.7874 -0.4064)
			(stroke
				(width 0.1524)
				(type default)
			)
			(layer "B.SilkS")
		)
		(fp_line
			(start -0.7874 -0.4064)
			(end -0.7874 0.4064)
			(stroke
				(width 0.1524)
				(type default)
			)
			(layer "B.SilkS")
		)
		(fp_line
			(start 0.7874 0.4064)
			(end 0.7874 -0.4064)
			(stroke
				(width 0.1524)
				(type default)
			)
			(layer "B.SilkS")
		)
		(fp_line
			(start -0.7874 0.4064)
			(end 0.7874 0.4064)
			(stroke
				(width 0.1524)
				(type default)
			)
			(layer "B.SilkS")
		)
		(fp_line
			(start 0.67945 -0.305054)
			(end 0.12065 -0.305054)
			(stroke
				(width 0.1)
				(type default)
			)
			(layer "B.Fab")
		)
		(fp_line
			(start 0.12065 -0.305054)
			(end 0.12065 -0.2794)
			(stroke
				(width 0.1)
				(type default)
			)
			(layer "B.Fab")
		)
		(fp_line
			(start -0.12065 -0.3048)
			(end -0.67945 -0.3048)
			(stroke
				(width 0.1)
				(type default)
			)
			(layer "B.Fab")
		)
		(fp_line
			(start -0.67945 -0.3048)
			(end -0.67945 0.3048)
			(stroke
				(width 0.1)
				(type default)
			)
			(layer "B.Fab")
		)
		(fp_line
			(start 0.12065 -0.2794)
			(end -0.12065 -0.2794)
			(stroke
				(width 0.1)
				(type default)
			)
			(layer "B.Fab")
		)
		(fp_line
			(start -0.12065 -0.2794)
			(end -0.12065 -0.3048)
			(stroke
				(width 0.1)
				(type default)
			)
			(layer "B.Fab")
		)
		(fp_line
			(start 0.12065 0.2794)
			(end 0.12065 0.3048)
			(stroke
				(width 0.1)
				(type default)
			)
			(layer "B.Fab")
		)
		(fp_line
			(start -0.120396 0.2794)
			(end 0.12065 0.2794)
			(stroke
				(width 0.1)
				(type default)
			)
			(layer "B.Fab")
		)
		(fp_line
			(start 0.67945 0.3048)
			(end 0.67945 -0.305054)
			(stroke
				(width 0.1)
				(type default)
			)
			(layer "B.Fab")
		)
		(fp_line
			(start 0.12065 0.3048)
			(end 0.67945 0.3048)
			(stroke
				(width 0.1)
				(type default)
			)
			(layer "B.Fab")
		)
		(fp_line
			(start -0.120396 0.3048)
			(end -0.120396 0.2794)
			(stroke
				(width 0.1)
				(type default)
			)
			(layer "B.Fab")
		)
		(fp_line
			(start -0.67945 0.3048)
			(end -0.120396 0.3048)
			(stroke
				(width 0.1)
				(type default)
			)
			(layer "B.Fab")
		)
		(pad "1" smd circle
			(at 0.40005 0 270)
			(size 0 0)
			(layers "B.Cu" "B.Mask" "B.Paste")
			(net "PVDDCR_SOC_P0_VOS3")
		)
		(pad "2" smd circle
			(at -0.40005 0 270)
			(size 0 0)
			(layers "B.Cu" "B.Mask" "B.Paste")
			(net "PVDDCR_SOC_P0")
		)
	)
)
